(kicad_pcb
	(version 20260206)
	(generator "pcbnew")
	(generator_version "10.0")
	(general
		(thickness 1.6)
		(legacy_teardrops no)
	)
	(paper "A4")
	(title_block
		(title "01162023_DA0F0TEBIF0_F0T_Expander_BD_F_brd_V02_OCP.brd")
		(comment 1 "Grand Teton / footprints 5548-5555 of 9728")
	)
	(layers
		(0 "F.Cu" signal "TOP")
		(4 "In1.Cu" signal "GND")
		(6 "In2.Cu" signal "VCC")
		(8 "In3.Cu" signal "VCC1")
		(10 "In4.Cu" signal "GND1")
		(12 "In5.Cu" signal "IN1")
		(14 "In6.Cu" signal "GND2")
		(16 "In7.Cu" signal "IN2")
		(18 "In8.Cu" signal "GND3")
		(20 "In9.Cu" signal "IN3")
		(22 "In10.Cu" signal "GND4")
		(24 "In11.Cu" signal "IN4")
		(26 "In12.Cu" signal "GND5")
		(28 "In13.Cu" signal "IN5")
		(30 "In14.Cu" signal "GND6")
		(32 "In15.Cu" signal "IN6")
		(34 "In16.Cu" signal "GND7")
		(2 "B.Cu" signal "BOTTOM")
		(9 "F.Adhes" user "F.Adhesive")
		(11 "B.Adhes" user "B.Adhesive")
		(13 "F.Paste" user "Package Geometry/Pastemask Top")
		(15 "B.Paste" user "Package Geometry/Pastemask Bottom")
		(5 "F.SilkS" user "Ref Des/Silkscreen Top")
		(7 "B.SilkS" user "Ref Des/Silkscreen Bottom")
		(1 "F.Mask" user "Board Geometry/Soldermask Top")
		(3 "B.Mask" user "Board Geometry/Soldermask Bottom")
		(17 "Dwgs.User" user "User.Drawings")
		(19 "Cmts.User" user "User.Comments")
		(21 "Eco1.User" user "User.Eco1")
		(23 "Eco2.User" user "User.Eco2")
		(25 "Edge.Cuts" user "Board Geometry/Outline")
		(27 "Margin" user)
		(31 "F.CrtYd" user "Package Geometry/Place Bound Top")
		(29 "B.CrtYd" user "Package Geometry/Place Bound Bottom")
		(35 "F.Fab" user "Ref Des/Assembly Top")
		(33 "B.Fab" user "Ref Des/Assembly Bottom")
	)
	(footprint ""
		(layer "F.Cu")
		(at 410.00299 -388.253732 180)
		(property "Reference" "C4160"
			(at 0 0 180)
			(layer "F.SilkS")
			(hide yes)
			(effects
				(font
					(size 1.27 1.27)
				)
			)
		)
		(property "Value" ""
			(at 0 0 180)
			(layer "F.Fab")
			(effects
				(font
					(size 1.27 1.27)
				)
			)
		)
		(duplicate_pad_numbers_are_jumpers no)
		(fp_line
			(start 0.7874 0.4064)
			(end -0.7874 0.4064)
			(stroke
				(width 0.1524)
				(type default)
			)
			(layer "F.SilkS")
		)
		(fp_line
			(start 0.7874 -0.4064)
			(end 0.7874 0.4064)
			(stroke
				(width 0.1524)
				(type default)
			)
			(layer "F.SilkS")
		)
		(fp_line
			(start -0.7874 0.4064)
			(end -0.7874 -0.4064)
			(stroke
				(width 0.1524)
				(type default)
			)
			(layer "F.SilkS")
		)
		(fp_line
			(start -0.7874 -0.4064)
			(end 0.7874 -0.4064)
			(stroke
				(width 0.1524)
				(type default)
			)
			(layer "F.SilkS")
		)
		(fp_line
			(start 0.67945 0.3048)
			(end 0.120396 0.3048)
			(stroke
				(width 0.1)
				(type default)
			)
			(layer "F.Fab")
		)
		(fp_line
			(start 0.67945 -0.3048)
			(end 0.67945 0.3048)
			(stroke
				(width 0.1)
				(type default)
			)
			(layer "F.Fab")
		)
		(fp_line
			(start 0.12065 -0.2794)
			(end 0.12065 -0.3048)
			(stroke
				(width 0.1)
				(type default)
			)
			(layer "F.Fab")
		)
		(fp_line
			(start 0.12065 -0.3048)
			(end 0.67945 -0.3048)
			(stroke
				(width 0.1)
				(type default)
			)
			(layer "F.Fab")
		)
		(fp_line
			(start 0.120396 0.3048)
			(end 0.120396 0.2794)
			(stroke
				(width 0.1)
				(type default)
			)
			(layer "F.Fab")
		)
		(fp_line
			(start 0.120396 0.2794)
			(end -0.12065 0.2794)
			(stroke
				(width 0.1)
				(type default)
			)
			(layer "F.Fab")
		)
		(fp_line
			(start -0.12065 0.3048)
			(end -0.67945 0.3048)
			(stroke
				(width 0.1)
				(type default)
			)
			(layer "F.Fab")
		)
		(fp_line
			(start -0.12065 0.2794)
			(end -0.12065 0.3048)
			(stroke
				(width 0.1)
				(type default)
			)
			(layer "F.Fab")
		)
		(fp_line
			(start -0.12065 -0.2794)
			(end 0.12065 -0.2794)
			(stroke
				(width 0.1)
				(type default)
			)
			(layer "F.Fab")
		)
		(fp_line
			(start -0.12065 -0.305054)
			(end -0.12065 -0.2794)
			(stroke
				(width 0.1)
				(type default)
			)
			(layer "F.Fab")
		)
		(fp_line
			(start -0.67945 0.3048)
			(end -0.67945 -0.305054)
			(stroke
				(width 0.1)
				(type default)
			)
			(layer "F.Fab")
		)
		(fp_line
			(start -0.67945 -0.305054)
			(end -0.12065 -0.305054)
			(stroke
				(width 0.1)
				(type default)
			)
			(layer "F.Fab")
		)
		(pad "1" smd circle
			(at -0.40005 0 180)
			(size 0 0)
			(layers "F.Cu" "F.Mask" "F.Paste")
			(net "GND")
		)
		(pad "2" smd circle
			(at 0.40005 0 180)
			(size 0 0)
			(layers "F.Cu" "F.Mask" "F.Paste")
			(net "GPU_3V3IO_RSVD3")
		)
	)
	(footprint ""
		(layer "F.Cu")
		(at 128.295908 -350.098614 90)
		(property "Reference" "C355"
			(at 0 0 90)
			(layer "F.SilkS")
			(hide yes)
			(effects
				(font
					(size 1.27 1.27)
				)
			)
		)
		(property "Value" ""
			(at 0 0 90)
			(layer "F.Fab")
			(effects
				(font
					(size 1.27 1.27)
				)
			)
		)
		(duplicate_pad_numbers_are_jumpers no)
		(fp_line
			(start 0.299974 -0.150114)
			(end 0.299974 0.150114)
			(stroke
				(width 0.1)
				(type default)
			)
			(layer "F.Fab")
		)
		(fp_line
			(start -0.299974 -0.150114)
			(end 0.299974 -0.150114)
			(stroke
				(width 0.1)
				(type default)
			)
			(layer "F.Fab")
		)
		(fp_line
			(start 0.299974 0.150114)
			(end -0.299974 0.150114)
			(stroke
				(width 0.1)
				(type default)
			)
			(layer "F.Fab")
		)
		(fp_line
			(start -0.299974 0.150114)
			(end -0.299974 -0.150114)
			(stroke
				(width 0.1)
				(type default)
			)
			(layer "F.Fab")
		)
		(pad "1" smd rect
			(at -0.2667 0 90)
			(size 0.3048 0.381)
			(layers "F.Cu" "F.Mask" "F.Paste")
			(net "P5E_PEX1_STN6_TX_DN<104>")
		)
		(pad "2" smd rect
			(at 0.2667 0 90)
			(size 0.3048 0.381)
			(layers "F.Cu" "F.Mask" "F.Paste")
			(net "P5E_PEX1_STN6_TX_C_DN<104>")
		)
	)
	(footprint ""
		(layer "F.Cu")
		(at 290.548822 -343.952322 90)
		(property "Reference" "C593"
			(at 0 0 90)
			(layer "F.SilkS")
			(hide yes)
			(effects
				(font
					(size 1.27 1.27)
				)
			)
		)
		(property "Value" ""
			(at 0 0 90)
			(layer "F.Fab")
			(effects
				(font
					(size 1.27 1.27)
				)
			)
		)
		(duplicate_pad_numbers_are_jumpers no)
		(fp_line
			(start 0.299974 -0.150114)
			(end 0.299974 0.150114)
			(stroke
				(width 0.1)
				(type default)
			)
			(layer "F.Fab")
		)
		(fp_line
			(start -0.299974 -0.150114)
			(end 0.299974 -0.150114)
			(stroke
				(width 0.1)
				(type default)
			)
			(layer "F.Fab")
		)
		(fp_line
			(start 0.299974 0.150114)
			(end -0.299974 0.150114)
			(stroke
				(width 0.1)
				(type default)
			)
			(layer "F.Fab")
		)
		(fp_line
			(start -0.299974 0.150114)
			(end -0.299974 -0.150114)
			(stroke
				(width 0.1)
				(type default)
			)
			(layer "F.Fab")
		)
		(pad "1" smd rect
			(at -0.2667 0 90)
			(size 0.3048 0.381)
			(layers "F.Cu" "F.Mask" "F.Paste")
			(net "P5E_PEX2_STN7_TX_DP<122>")
		)
		(pad "2" smd rect
			(at 0.2667 0 90)
			(size 0.3048 0.381)
			(layers "F.Cu" "F.Mask" "F.Paste")
			(net "P5E_PEX2_STN7_TX_C_DP<122>")
		)
	)
	(footprint ""
		(layer "F.Cu")
		(at 185.722768 -22.867366 90)
		(property "Reference" "C3917"
			(at 0 0 90)
			(layer "F.SilkS")
			(hide yes)
			(effects
				(font
					(size 1.27 1.27)
				)
			)
		)
		(property "Value" ""
			(at 0 0 90)
			(layer "F.Fab")
			(effects
				(font
					(size 1.27 1.27)
				)
			)
		)
		(duplicate_pad_numbers_are_jumpers no)
		(fp_line
			(start 0.7874 -0.4064)
			(end 0.7874 0.4064)
			(stroke
				(width 0.1524)
				(type default)
			)
			(layer "F.SilkS")
		)
		(fp_line
			(start -0.7874 -0.4064)
			(end 0.7874 -0.4064)
			(stroke
				(width 0.1524)
				(type default)
			)
			(layer "F.SilkS")
		)
		(fp_line
			(start 0.7874 0.4064)
			(end -0.7874 0.4064)
			(stroke
				(width 0.1524)
				(type default)
			)
			(layer "F.SilkS")
		)
		(fp_line
			(start -0.7874 0.4064)
			(end -0.7874 -0.4064)
			(stroke
				(width 0.1524)
				(type default)
			)
			(layer "F.SilkS")
		)
		(fp_line
			(start -0.12065 -0.305054)
			(end -0.12065 -0.2794)
			(stroke
				(width 0.1)
				(type default)
			)
			(layer "F.Fab")
		)
		(fp_line
			(start -0.67945 -0.305054)
			(end -0.12065 -0.305054)
			(stroke
				(width 0.1)
				(type default)
			)
			(layer "F.Fab")
		)
		(fp_line
			(start 0.67945 -0.3048)
			(end 0.67945 0.3048)
			(stroke
				(width 0.1)
				(type default)
			)
			(layer "F.Fab")
		)
		(fp_line
			(start 0.12065 -0.3048)
			(end 0.67945 -0.3048)
			(stroke
				(width 0.1)
				(type default)
			)
			(layer "F.Fab")
		)
		(fp_line
			(start 0.12065 -0.2794)
			(end 0.12065 -0.3048)
			(stroke
				(width 0.1)
				(type default)
			)
			(layer "F.Fab")
		)
		(fp_line
			(start -0.12065 -0.2794)
			(end 0.12065 -0.2794)
			(stroke
				(width 0.1)
				(type default)
			)
			(layer "F.Fab")
		)
		(fp_line
			(start 0.120396 0.2794)
			(end -0.12065 0.2794)
			(stroke
				(width 0.1)
				(type default)
			)
			(layer "F.Fab")
		)
		(fp_line
			(start -0.12065 0.2794)
			(end -0.12065 0.3048)
			(stroke
				(width 0.1)
				(type default)
			)
			(layer "F.Fab")
		)
		(fp_line
			(start 0.67945 0.3048)
			(end 0.120396 0.3048)
			(stroke
				(width 0.1)
				(type default)
			)
			(layer "F.Fab")
		)
		(fp_line
			(start 0.120396 0.3048)
			(end 0.120396 0.2794)
			(stroke
				(width 0.1)
				(type default)
			)
			(layer "F.Fab")
		)
		(fp_line
			(start -0.12065 0.3048)
			(end -0.67945 0.3048)
			(stroke
				(width 0.1)
				(type default)
			)
			(layer "F.Fab")
		)
		(fp_line
			(start -0.67945 0.3048)
			(end -0.67945 -0.305054)
			(stroke
				(width 0.1)
				(type default)
			)
			(layer "F.Fab")
		)
		(pad "1" smd circle
			(at -0.40005 0 90)
			(size 0 0)
			(layers "F.Cu" "F.Mask" "F.Paste")
			(net "P12V_SSD6")
		)
		(pad "2" smd circle
			(at 0.40005 0 90)
			(size 0 0)
			(layers "F.Cu" "F.Mask" "F.Paste")
			(net "GND")
		)
	)
	(footprint ""
		(layer "F.Cu")
		(at 101.689154 -220.544644)
		(property "Reference" "R851"
			(at 0 0 0)
			(layer "F.SilkS")
			(hide yes)
			(effects
				(font
					(size 1.27 1.27)
				)
			)
		)
		(property "Value" ""
			(at 0 0 0)
			(layer "F.Fab")
			(effects
				(font
					(size 1.27 1.27)
				)
			)
		)
		(duplicate_pad_numbers_are_jumpers no)
		(fp_line
			(start -0.7874 -0.4064)
			(end 0.7874 -0.4064)
			(stroke
				(width 0.1524)
				(type default)
			)
			(layer "F.SilkS")
		)
		(fp_line
			(start -0.7874 0.4064)
			(end -0.7874 -0.4064)
			(stroke
				(width 0.1524)
				(type default)
			)
			(layer "F.SilkS")
		)
		(fp_line
			(start 0.7874 -0.4064)
			(end 0.7874 0.4064)
			(stroke
				(width 0.1524)
				(type default)
			)
			(layer "F.SilkS")
		)
		(fp_line
			(start 0.7874 0.4064)
			(end -0.7874 0.4064)
			(stroke
				(width 0.1524)
				(type default)
			)
			(layer "F.SilkS")
		)
		(fp_line
			(start -0.67945 -0.305054)
			(end -0.12065 -0.305054)
			(stroke
				(width 0.1)
				(type default)
			)
			(layer "F.Fab")
		)
		(fp_line
			(start -0.67945 0.3048)
			(end -0.67945 -0.305054)
			(stroke
				(width 0.1)
				(type default)
			)
			(layer "F.Fab")
		)
		(fp_line
			(start -0.12065 -0.305054)
			(end -0.12065 -0.2794)
			(stroke
				(width 0.1)
				(type default)
			)
			(layer "F.Fab")
		)
		(fp_line
			(start -0.12065 -0.2794)
			(end 0.12065 -0.2794)
			(stroke
				(width 0.1)
				(type default)
			)
			(layer "F.Fab")
		)
		(fp_line
			(start -0.12065 0.2794)
			(end -0.12065 0.3048)
			(stroke
				(width 0.1)
				(type default)
			)
			(layer "F.Fab")
		)
		(fp_line
			(start -0.12065 0.3048)
			(end -0.67945 0.3048)
			(stroke
				(width 0.1)
				(type default)
			)
			(layer "F.Fab")
		)
		(fp_line
			(start 0.120396 0.2794)
			(end -0.12065 0.2794)
			(stroke
				(width 0.1)
				(type default)
			)
			(layer "F.Fab")
		)
		(fp_line
			(start 0.120396 0.3048)
			(end 0.120396 0.2794)
			(stroke
				(width 0.1)
				(type default)
			)
			(layer "F.Fab")
		)
		(fp_line
			(start 0.12065 -0.3048)
			(end 0.67945 -0.3048)
			(stroke
				(width 0.1)
				(type default)
			)
			(layer "F.Fab")
		)
		(fp_line
			(start 0.12065 -0.2794)
			(end 0.12065 -0.3048)
			(stroke
				(width 0.1)
				(type default)
			)
			(layer "F.Fab")
		)
		(fp_line
			(start 0.67945 -0.3048)
			(end 0.67945 0.3048)
			(stroke
				(width 0.1)
				(type default)
			)
			(layer "F.Fab")
		)
		(fp_line
			(start 0.67945 0.3048)
			(end 0.120396 0.3048)
			(stroke
				(width 0.1)
				(type default)
			)
			(layer "F.Fab")
		)
		(pad "1" smd circle
			(at -0.40005 0)
			(size 0 0)
			(layers "F.Cu" "F.Mask" "F.Paste")
			(net "PWR_EN_PEX_R")
		)
		(pad "2" smd circle
			(at 0.40005 0)
			(size 0 0)
			(layers "F.Cu" "F.Mask" "F.Paste")
			(net "P1V8_PEX_EN")
		)
	)
	(footprint ""
		(layer "F.Cu")
		(at 233.762804 -276.534118 180)
		(property "Reference" "C4334"
			(at 0 0 180)
			(layer "F.SilkS")
			(hide yes)
			(effects
				(font
					(size 1.27 1.27)
				)
			)
		)
		(property "Value" ""
			(at 0 0 180)
			(layer "F.Fab")
			(effects
				(font
					(size 1.27 1.27)
				)
			)
		)
		(duplicate_pad_numbers_are_jumpers no)
		(fp_line
			(start 0.299974 0.150114)
			(end -0.299974 0.150114)
			(stroke
				(width 0.1)
				(type default)
			)
			(layer "F.Fab")
		)
		(fp_line
			(start 0.299974 -0.150114)
			(end 0.299974 0.150114)
			(stroke
				(width 0.1)
				(type default)
			)
			(layer "F.Fab")
		)
		(fp_line
			(start -0.299974 0.150114)
			(end -0.299974 -0.150114)
			(stroke
				(width 0.1)
				(type default)
			)
			(layer "F.Fab")
		)
		(fp_line
			(start -0.299974 -0.150114)
			(end 0.299974 -0.150114)
			(stroke
				(width 0.1)
				(type default)
			)
			(layer "F.Fab")
		)
		(pad "1" smd rect
			(at -0.2667 0 180)
			(size 0.3048 0.381)
			(layers "F.Cu" "F.Mask" "F.Paste")
			(net "P1V25_PEX2")
		)
		(pad "2" smd rect
			(at 0.2667 0 180)
			(size 0.3048 0.381)
			(layers "F.Cu" "F.Mask" "F.Paste")
			(net "GND")
		)
	)
	(footprint ""
		(layer "F.Cu")
		(at 248.897902 -80.2894 180)
		(property "Reference" "Y6"
			(at 0.384302 -2.71907 0)
			(unlocked yes)
			(layer "F.SilkS")
			(effects
				(font
					(size 0.7874 0.5842)
					(thickness 0.1524)
				)
				(justify left)
			)
		)
		(property "Value" ""
			(at 0 0 180)
			(layer "F.Fab")
			(effects
				(font
					(size 1.27 1.27)
				)
			)
		)
		(duplicate_pad_numbers_are_jumpers no)
		(fp_line
			(start 1.538732 1.937004)
			(end -1.538732 1.937004)
			(stroke
				(width 0.1524)
				(type default)
			)
			(layer "F.SilkS")
		)
		(fp_line
			(start 1.538732 -1.937004)
			(end 1.538732 1.937004)
			(stroke
				(width 0.1524)
				(type default)
			)
			(layer "F.SilkS")
		)
		(fp_line
			(start -1.538732 1.937004)
			(end -1.538732 -1.937004)
			(stroke
				(width 0.1524)
				(type default)
			)
			(layer "F.SilkS")
		)
		(fp_line
			(start -1.538732 -1.937004)
			(end 1.538732 -1.937004)
			(stroke
				(width 0.1524)
				(type default)
			)
			(layer "F.SilkS")
		)
		(fp_poly
			(pts
				(xy -2.752598 -2.392934) (xy -2.13995 -3.005582) (xy -1.83388 -2.086356)
			)
			(stroke
				(width 0)
				(type default)
			)
			(fill yes)
			(layer "F.SilkS")
		)
		(fp_line
			(start 1.299972 1.649984)
			(end -1.299972 1.649984)
			(stroke
				(width 0.1)
				(type default)
			)
			(layer "F.Fab")
		)
		(fp_line
			(start 1.299972 -1.649984)
			(end 1.299972 1.649984)
			(stroke
				(width 0.1)
				(type default)
			)
			(layer "F.Fab")
		)
		(fp_line
			(start -1.299972 1.649984)
			(end -1.299972 -1.649984)
			(stroke
				(width 0.1)
				(type default)
			)
			(layer "F.Fab")
		)
		(fp_line
			(start -1.299972 -1.649984)
			(end 1.299972 -1.649984)
			(stroke
				(width 0.1)
				(type default)
			)
			(layer "F.Fab")
		)
		(fp_poly
			(pts
				(xy -2.5908 -0.626872) (xy -2.5908 -1.493266) (xy -1.724406 -1.059942)
			)
			(stroke
				(width 0)
				(type default)
			)
			(fill yes)
			(layer "F.Fab")
		)
		(pad "1" smd rect
			(at -0.8001 -1.059942 180)
			(size 1.2192 1.4986)
			(layers "F.Cu" "F.Mask" "F.Paste")
			(net "XTAL_CK440_25M_R_XIN")
		)
		(pad "2" smd rect
			(at -0.8001 1.059942 180)
			(size 1.2192 1.4986)
			(layers "F.Cu" "F.Mask" "F.Paste")
			(net "GND")
		)
		(pad "3" smd rect
			(at 0.8001 1.059942 180)
			(size 1.2192 1.4986)
			(layers "F.Cu" "F.Mask" "F.Paste")
			(net "XTAL_CK440_25M_XOUT")
		)
		(pad "4" smd rect
			(at 0.8001 -1.059942 180)
			(size 1.2192 1.4986)
			(layers "F.Cu" "F.Mask" "F.Paste")
			(net "GND")
		)
	)
	(footprint ""
		(layer "F.Cu")
		(at 259.022596 -311.156604 -90)
		(property "Reference" "R1394"
			(at 0 0 270)
			(layer "F.SilkS")
			(hide yes)
			(effects
				(font
					(size 1.27 1.27)
				)
			)
		)
		(property "Value" ""
			(at 0 0 270)
			(layer "F.Fab")
			(effects
				(font
					(size 1.27 1.27)
				)
			)
		)
		(duplicate_pad_numbers_are_jumpers no)
		(fp_line
			(start -0.7874 0.4064)
			(end -0.7874 -0.4064)
			(stroke
				(width 0.1524)
				(type default)
			)
			(layer "F.SilkS")
		)
		(fp_line
			(start 0.7874 0.4064)
			(end -0.7874 0.4064)
			(stroke
				(width 0.1524)
				(type default)
			)
			(layer "F.SilkS")
		)
		(fp_line
			(start -0.7874 -0.4064)
			(end 0.7874 -0.4064)
			(stroke
				(width 0.1524)
				(type default)
			)
			(layer "F.SilkS")
		)
		(fp_line
			(start 0.7874 -0.4064)
			(end 0.7874 0.4064)
			(stroke
				(width 0.1524)
				(type default)
			)
			(layer "F.SilkS")
		)
		(fp_line
			(start -0.67945 0.3048)
			(end -0.67945 -0.305054)
			(stroke
				(width 0.1)
				(type default)
			)
			(layer "F.Fab")
		)
		(fp_line
			(start -0.12065 0.3048)
			(end -0.67945 0.3048)
			(stroke
				(width 0.1)
				(type default)
			)
			(layer "F.Fab")
		)
		(fp_line
			(start 0.120396 0.3048)
			(end 0.120396 0.2794)
			(stroke
				(width 0.1)
				(type default)
			)
			(layer "F.Fab")
		)
		(fp_line
			(start 0.67945 0.3048)
			(end 0.120396 0.3048)
			(stroke
				(width 0.1)
				(type default)
			)
			(layer "F.Fab")
		)
		(fp_line
			(start -0.12065 0.2794)
			(end -0.12065 0.3048)
			(stroke
				(width 0.1)
				(type default)
			)
			(layer "F.Fab")
		)
		(fp_line
			(start 0.120396 0.2794)
			(end -0.12065 0.2794)
			(stroke
				(width 0.1)
				(type default)
			)
			(layer "F.Fab")
		)
		(fp_line
			(start -0.12065 -0.2794)
			(end 0.12065 -0.2794)
			(stroke
				(width 0.1)
				(type default)
			)
			(layer "F.Fab")
		)
		(fp_line
			(start 0.12065 -0.2794)
			(end 0.12065 -0.3048)
			(stroke
				(width 0.1)
				(type default)
			)
			(layer "F.Fab")
		)
		(fp_line
			(start 0.12065 -0.3048)
			(end 0.67945 -0.3048)
			(stroke
				(width 0.1)
				(type default)
			)
			(layer "F.Fab")
		)
		(fp_line
			(start 0.67945 -0.3048)
			(end 0.67945 0.3048)
			(stroke
				(width 0.1)
				(type default)
			)
			(layer "F.Fab")
		)
		(fp_line
			(start -0.67945 -0.305054)
			(end -0.12065 -0.305054)
			(stroke
				(width 0.1)
				(type default)
			)
			(layer "F.Fab")
		)
		(fp_line
			(start -0.12065 -0.305054)
			(end -0.12065 -0.2794)
			(stroke
				(width 0.1)
				(type default)
			)
			(layer "F.Fab")
		)
		(pad "1" smd circle
			(at -0.40005 0 270)
			(size 0 0)
			(layers "F.Cu" "F.Mask" "F.Paste")
			(net "PU_PEX2_TR_TCK")
		)
		(pad "2" smd circle
			(at 0.40005 0 270)
			(size 0 0)
			(layers "F.Cu" "F.Mask" "F.Paste")
			(net "P1V8_PEX")
		)
	)
)
